(kicad_pcb
	(version 20260206)
	(generator "pcbnew")
	(generator_version "10.0")
	(general
		(thickness 1.6)
		(legacy_teardrops no)
	)
	(paper "A4")
	(title_block
		(title "Bryce Canyon_R.DPB_16317-1_OCP.brd")
		(comment 1 "Bryce Canyon / footprints 789-795 of 2099")
	)
	(layers
		(0 "F.Cu" signal "TOP")
		(4 "In1.Cu" signal "L2GND")
		(6 "In2.Cu" signal "L3")
		(8 "In3.Cu" signal "L4VCC")
		(10 "In4.Cu" signal "L5VCC")
		(12 "In5.Cu" signal "L6")
		(14 "In6.Cu" signal "L7GND")
		(2 "B.Cu" signal "BOTTOM")
		(9 "F.Adhes" user "F.Adhesive")
		(11 "B.Adhes" user "B.Adhesive")
		(13 "F.Paste" user "Package Geometry/Pastemask Top")
		(15 "B.Paste" user "Package Geometry/Pastemask Bottom")
		(5 "F.SilkS" user "Ref Des/Silkscreen Top")
		(7 "B.SilkS" user "Ref Des/Silkscreen Bottom")
		(1 "F.Mask" user "Board Geometry/Soldermask Top")
		(3 "B.Mask" user "Board Geometry/Soldermask Bottom")
		(17 "Dwgs.User" user "User.Drawings")
		(19 "Cmts.User" user "User.Comments")
		(21 "Eco1.User" user "User.Eco1")
		(23 "Eco2.User" user "User.Eco2")
		(25 "Edge.Cuts" user "Board Geometry/Outline")
		(27 "Margin" user)
		(31 "F.CrtYd" user "Package Geometry/Place Bound Top")
		(29 "B.CrtYd" user "Package Geometry/Place Bound Bottom")
		(35 "F.Fab" user "Ref Des/Assembly Top")
		(33 "B.Fab" user "Ref Des/Assembly Bottom")
	)
	(footprint ""
		(layer "F.Cu")
		(at 148.2217 -130.6957 180)
		(property "Reference" "R449"
			(at 0 0 180)
			(layer "F.SilkS")
			(hide yes)
			(effects
				(font
					(size 1.27 1.27)
				)
			)
		)
		(property "Value" "0R2J-2-GP"
			(at 0.064008 -3.993896 180)
			(unlocked yes)
			(layer "F.Fab")
			(hide yes)
			(effects
				(font
					(size 1.016 1.016)
					(thickness 0.1524)
				)
			)
		)
		(property "Device Type" "R402H16"
			(at 0.064008 -5.517896 180)
			(unlocked yes)
			(layer "F.Fab")
			(hide yes)
			(effects
				(font
					(size 1.016 1.016)
					(thickness 0.1524)
				)
			)
		)
		(duplicate_pad_numbers_are_jumpers no)
		(fp_line
			(start 0.508 -0.9398)
			(end -0.508 -0.9398)
			(stroke
				(width 0.1524)
				(type default)
			)
			(layer "F.SilkS")
		)
		(fp_line
			(start -0.508 -0.9398)
			(end -0.508 0.9398)
			(stroke
				(width 0.1524)
				(type default)
			)
			(layer "F.SilkS")
		)
		(fp_rect
			(start -0.508 0.9398)
			(end 0.508 -0.9398)
			(stroke
				(width 0)
				(type default)
			)
			(fill no)
			(layer "F.CrtYd")
		)
		(fp_rect
			(start -0.508 0.9398)
			(end 0.508 -0.9398)
			(stroke
				(width 0)
				(type default)
			)
			(fill no)
			(layer "F.Fab")
		)
		(pad "1" smd custom
			(at 0 -0.4445 180)
			(size 0.1397 0.1397)
			(layers "F.Cu" "F.Mask" "F.Paste")
			(net "DRIVE_B_16_PWR")
			(options
				(clearance outline)
				(anchor circle)
			)
			(primitives
				(gr_poly
					(pts
						(arc
							(start -0.1778 -0.2794)
							(mid -0.249642 -0.249642)
							(end -0.2794 -0.1778)
						)
						(arc
							(start -0.2794 0.1778)
							(mid -0.249642 0.249642)
							(end -0.1778 0.2794)
						)
						(arc
							(start 0.1778 0.2794)
							(mid 0.249642 0.249642)
							(end 0.2794 0.1778)
						)
						(arc
							(start 0.2794 -0.1778)
							(mid 0.249642 -0.249642)
							(end 0.1778 -0.2794)
						)
					)
					(width 0)
					(fill yes)
				)
			)
		)
		(pad "2" smd custom
			(at 0 0.4445 180)
			(size 0.1397 0.1397)
			(layers "F.Cu" "F.Mask" "F.Paste")
			(net "SW_PWR_R_HDD16")
			(options
				(clearance outline)
				(anchor circle)
			)
			(primitives
				(gr_poly
					(pts
						(arc
							(start -0.1778 -0.2794)
							(mid -0.249642 -0.249642)
							(end -0.2794 -0.1778)
						)
						(arc
							(start -0.2794 0.1778)
							(mid -0.249642 0.249642)
							(end -0.1778 0.2794)
						)
						(arc
							(start 0.1778 0.2794)
							(mid 0.249642 0.249642)
							(end 0.2794 0.1778)
						)
						(arc
							(start 0.2794 -0.1778)
							(mid 0.249642 -0.249642)
							(end 0.1778 -0.2794)
						)
					)
					(width 0)
					(fill yes)
				)
			)
		)
	)
	(footprint ""
		(layer "F.Cu")
		(at 473.964 -265.684 90)
		(property "Reference" "R336"
			(at 0 0 90)
			(layer "F.SilkS")
			(hide yes)
			(effects
				(font
					(size 1.27 1.27)
				)
			)
		)
		(property "Value" "2R6F-GP"
			(at -0.0508 -4.8514 90)
			(unlocked yes)
			(layer "F.Fab")
			(hide yes)
			(effects
				(font
					(size 1.016 1.016)
					(thickness 0.1524)
				)
			)
		)
		(property "Device Type" "R1206H26"
			(at 0 -6.3754 90)
			(unlocked yes)
			(layer "F.Fab")
			(hide yes)
			(effects
				(font
					(size 1.016 1.016)
					(thickness 0.1524)
				)
			)
		)
		(duplicate_pad_numbers_are_jumpers no)
		(fp_line
			(start 1.016 -2.2352)
			(end 1.016 2.2352)
			(stroke
				(width 0.1524)
				(type default)
			)
			(layer "F.SilkS")
		)
		(fp_line
			(start -1.016 -2.2352)
			(end 1.016 -2.2352)
			(stroke
				(width 0.1524)
				(type default)
			)
			(layer "F.SilkS")
		)
		(fp_line
			(start 1.016 2.2352)
			(end -1.016 2.2352)
			(stroke
				(width 0.1524)
				(type default)
			)
			(layer "F.SilkS")
		)
		(fp_line
			(start -1.016 2.2352)
			(end -1.016 -2.2352)
			(stroke
				(width 0.1524)
				(type default)
			)
			(layer "F.SilkS")
		)
		(fp_rect
			(start -1.0922 2.3114)
			(end 1.0922 -2.3114)
			(stroke
				(width 0)
				(type default)
			)
			(fill no)
			(layer "F.CrtYd")
		)
		(fp_poly
			(pts
				(xy -1.0922 -2.3114) (xy 1.0922 -2.3114) (xy 1.0922 2.3114) (xy -1.0922 2.3114)
			)
			(stroke
				(width 0)
				(type default)
			)
			(fill no)
			(layer "F.Fab")
		)
		(pad "1" smd rect
			(at 0 -1.397 90)
			(size 1.651 1.27)
			(layers "F.Cu" "F.Mask" "F.Paste")
			(net "P12V_HDD11")
		)
		(pad "2" smd rect
			(at 0 1.397 90)
			(size 1.651 1.27)
			(layers "F.Cu" "F.Mask" "F.Paste")
			(net "12V_PRE_11")
		)
	)
	(footprint ""
		(layer "F.Cu")
		(at 97.385632 -129.99085 90)
		(property "Reference" "VIA29"
			(at 0 0 90)
			(layer "F.SilkS")
			(hide yes)
			(effects
				(font
					(size 1.27 1.27)
				)
			)
		)
		(property "Value" "100OHM-8L-2D36MM-L18-GP"
			(at 3.8989 0.5715 90)
			(unlocked yes)
			(layer "F.Fab")
			(hide yes)
			(effects
				(font
					(size 1.016 1.016)
					(thickness 0.1524)
				)
			)
		)
		(property "Device Type" "VIA-PCIE-4P-414097"
			(at 3.8989 -0.9525 90)
			(unlocked yes)
			(layer "F.Fab")
			(hide yes)
			(effects
				(font
					(size 1.016 1.016)
					(thickness 0.1524)
				)
			)
		)
		(duplicate_pad_numbers_are_jumpers no)
		(fp_rect
			(start -2.0701 0.4826)
			(end 2.0701 -0.4826)
			(stroke
				(width 0)
				(type default)
			)
			(fill no)
			(layer "F.CrtYd")
		)
		(fp_rect
			(start -2.0701 0.4826)
			(end 2.0701 -0.4826)
			(stroke
				(width 0)
				(type default)
			)
			(fill no)
			(layer "F.Fab")
		)
		(pad "1" thru_hole circle
			(at -1.5875 0 90)
			(size 0.508 0.508)
			(drill 0.254)
			(layers "*.Cu" "*.Mask")
			(remove_unused_layers no)
			(net "GND")
			(clearance 0.2286)
			(thermal_gap 0.2286)
		)
		(pad "2" thru_hole circle
			(at -0.5715 0 90)
			(size 0.508 0.508)
			(drill 0.254)
			(layers "*.Cu" "*.Mask")
			(remove_unused_layers no)
			(net "PHY_SCC_B_TO_DRV_B_14_DP")
			(clearance 0.2286)
			(thermal_gap 0.2286)
		)
		(pad "3" thru_hole circle
			(at 0.5715 0 90)
			(size 0.508 0.508)
			(drill 0.254)
			(layers "*.Cu" "*.Mask")
			(remove_unused_layers no)
			(net "PHY_SCC_B_TO_DRV_B_14_DN")
			(clearance 0.2286)
			(thermal_gap 0.2286)
		)
		(pad "4" thru_hole circle
			(at 1.5875 0 90)
			(size 0.508 0.508)
			(drill 0.254)
			(layers "*.Cu" "*.Mask")
			(remove_unused_layers no)
			(net "GND")
			(clearance 0.2286)
			(thermal_gap 0.2286)
		)
	)
	(footprint ""
		(layer "F.Cu")
		(at 163.87953 -362.132626 90)
		(property "Reference" "R1010"
			(at 0 0 90)
			(layer "F.SilkS")
			(hide yes)
			(effects
				(font
					(size 1.27 1.27)
				)
			)
		)
		(property "Value" "49K9R2F-L-GP"
			(at 0.064008 -3.993896 90)
			(unlocked yes)
			(layer "F.Fab")
			(hide yes)
			(effects
				(font
					(size 1.016 1.016)
					(thickness 0.1524)
				)
			)
		)
		(property "Device Type" "R402H16"
			(at 0.064008 -5.517896 90)
			(unlocked yes)
			(layer "F.Fab")
			(hide yes)
			(effects
				(font
					(size 1.016 1.016)
					(thickness 0.1524)
				)
			)
		)
		(duplicate_pad_numbers_are_jumpers no)
		(fp_line
			(start 0.508 -0.9398)
			(end -0.508 -0.9398)
			(stroke
				(width 0.1524)
				(type default)
			)
			(layer "F.SilkS")
		)
		(fp_line
			(start -0.508 -0.9398)
			(end -0.508 0.9398)
			(stroke
				(width 0.1524)
				(type default)
			)
			(layer "F.SilkS")
		)
		(fp_rect
			(start -0.508 0.9398)
			(end 0.508 -0.9398)
			(stroke
				(width 0)
				(type default)
			)
			(fill no)
			(layer "F.CrtYd")
		)
		(fp_rect
			(start -0.508 0.9398)
			(end 0.508 -0.9398)
			(stroke
				(width 0)
				(type default)
			)
			(fill no)
			(layer "F.Fab")
		)
		(pad "1" smd custom
			(at 0 -0.4445 90)
			(size 0.1397 0.1397)
			(layers "F.Cu" "F.Mask" "F.Paste")
			(net "P12V_CLIP")
			(options
				(clearance outline)
				(anchor circle)
			)
			(primitives
				(gr_poly
					(pts
						(arc
							(start -0.1778 -0.2794)
							(mid -0.249642 -0.249642)
							(end -0.2794 -0.1778)
						)
						(arc
							(start -0.2794 0.1778)
							(mid -0.249642 0.249642)
							(end -0.1778 0.2794)
						)
						(arc
							(start 0.1778 0.2794)
							(mid 0.249642 0.249642)
							(end 0.2794 0.1778)
						)
						(arc
							(start 0.2794 -0.1778)
							(mid 0.249642 -0.249642)
							(end 0.1778 -0.2794)
						)
					)
					(width 0)
					(fill yes)
				)
			)
		)
		(pad "2" smd custom
			(at 0 0.4445 90)
			(size 0.1397 0.1397)
			(layers "F.Cu" "F.Mask" "F.Paste")
			(net "MB0_CM_OV_R")
			(options
				(clearance outline)
				(anchor circle)
			)
			(primitives
				(gr_poly
					(pts
						(arc
							(start -0.1778 -0.2794)
							(mid -0.249642 -0.249642)
							(end -0.2794 -0.1778)
						)
						(arc
							(start -0.2794 0.1778)
							(mid -0.249642 0.249642)
							(end -0.1778 0.2794)
						)
						(arc
							(start 0.1778 0.2794)
							(mid 0.249642 0.249642)
							(end 0.2794 0.1778)
						)
						(arc
							(start 0.2794 -0.1778)
							(mid 0.249642 -0.249642)
							(end 0.1778 -0.2794)
						)
					)
					(width 0)
					(fill yes)
				)
			)
		)
	)
	(footprint ""
		(layer "F.Cu")
		(at 279.4 -378.000006 180)
		(property "Reference" "LED25"
			(at 0 0 180)
			(layer "F.SilkS")
			(hide yes)
			(effects
				(font
					(size 1.27 1.27)
				)
			)
		)
		(property "Value" "LED-IR-43-GP"
			(at -3.7846 1.0668 180)
			(unlocked yes)
			(layer "F.Fab")
			(hide yes)
			(effects
				(font
					(size 1.016 1.016)
					(thickness 0.1524)
				)
			)
		)
		(property "Device Type" "LED4036-2A1KH168"
			(at -3.7846 -0.4572 180)
			(unlocked yes)
			(layer "F.Fab")
			(hide yes)
			(effects
				(font
					(size 1.016 1.016)
					(thickness 0.1524)
				)
			)
		)
		(duplicate_pad_numbers_are_jumpers no)
		(fp_line
			(start 2.6162 2.54)
			(end 2.6162 1.27)
			(stroke
				(width 0.508)
				(type default)
			)
			(layer "F.SilkS")
		)
		(fp_line
			(start 2.4384 2.3622)
			(end 2.4384 -2.3622)
			(stroke
				(width 0.1524)
				(type default)
			)
			(layer "F.SilkS")
		)
		(fp_line
			(start 2.4384 -2.3622)
			(end -2.2606 -2.3622)
			(stroke
				(width 0.1524)
				(type default)
			)
			(layer "F.SilkS")
		)
		(fp_line
			(start -2.2606 2.3622)
			(end 2.4384 2.3622)
			(stroke
				(width 0.1524)
				(type default)
			)
			(layer "F.SilkS")
		)
		(fp_line
			(start -2.2606 -2.3622)
			(end -2.2606 2.3622)
			(stroke
				(width 0.1524)
				(type default)
			)
			(layer "F.SilkS")
		)
		(fp_line
			(start -2.4384 2.54)
			(end 2.6162 2.54)
			(stroke
				(width 0.508)
				(type default)
			)
			(layer "F.SilkS")
		)
		(fp_line
			(start -2.4384 1.27)
			(end -2.4384 2.54)
			(stroke
				(width 0.508)
				(type default)
			)
			(layer "F.SilkS")
		)
		(fp_rect
			(start -1.4224 1.9939)
			(end 2.1844 -1.9939)
			(stroke
				(width 0)
				(type default)
			)
			(fill no)
			(layer "F.CrtYd")
		)
		(fp_poly
			(pts
				(xy -2.5146 2.4384) (xy -2.5146 -2.4384) (xy 2.6924 -2.4384) (xy 2.6924 -0.00635) (xy 2.1844 -0.00635)
				(xy 2.1844 -1.9939) (xy -1.4224 -1.9939) (xy -1.4224 1.9939) (xy 2.1844 1.9939) (xy 2.1844 0.00635)
				(xy 2.6924 0.00635) (xy 2.6924 2.4384)
			)
			(stroke
				(width 0)
				(type default)
			)
			(fill no)
			(layer "F.CrtYd")
		)
		(fp_rect
			(start -2.5146 2.4384)
			(end 2.6924 -2.4384)
			(stroke
				(width 0)
				(type default)
			)
			(fill no)
			(layer "F.Fab")
		)
		(pad "1K" smd rect
			(at 0 1.249934 180)
			(size 3.9878 1.7018)
			(layers "F.Cu" "F.Mask" "F.Paste")
			(net "EMITTER_K")
		)
		(pad "2A" smd rect
			(at 0 -1.249934 180)
			(size 3.9878 1.7018)
			(layers "F.Cu" "F.Mask" "F.Paste")
			(net "P3V3_IN")
		)
	)
	(footprint ""
		(layer "F.Cu")
		(at 248.285 -305.054 90)
		(property "Reference" "R1088"
			(at 0 0 90)
			(layer "F.SilkS")
			(hide yes)
			(effects
				(font
					(size 1.27 1.27)
				)
			)
		)
		(property "Value" "0R2J-2-GP"
			(at 0.064008 -3.993896 90)
			(unlocked yes)
			(layer "F.Fab")
			(hide yes)
			(effects
				(font
					(size 1.016 1.016)
					(thickness 0.1524)
				)
			)
		)
		(property "Device Type" "R402H16"
			(at 0.064008 -5.517896 90)
			(unlocked yes)
			(layer "F.Fab")
			(hide yes)
			(effects
				(font
					(size 1.016 1.016)
					(thickness 0.1524)
				)
			)
		)
		(duplicate_pad_numbers_are_jumpers no)
		(fp_line
			(start 0.508 -0.9398)
			(end -0.508 -0.9398)
			(stroke
				(width 0.1524)
				(type default)
			)
			(layer "F.SilkS")
		)
		(fp_line
			(start -0.508 -0.9398)
			(end -0.508 0.9398)
			(stroke
				(width 0.1524)
				(type default)
			)
			(layer "F.SilkS")
		)
		(fp_rect
			(start -0.508 0.9398)
			(end 0.508 -0.9398)
			(stroke
				(width 0)
				(type default)
			)
			(fill no)
			(layer "F.CrtYd")
		)
		(fp_rect
			(start -0.508 0.9398)
			(end 0.508 -0.9398)
			(stroke
				(width 0)
				(type default)
			)
			(fill no)
			(layer "F.Fab")
		)
		(pad "1" smd custom
			(at 0 -0.4445 90)
			(size 0.1397 0.1397)
			(layers "F.Cu" "F.Mask" "F.Paste")
			(net "MAX31790_A_SCL")
			(options
				(clearance outline)
				(anchor circle)
			)
			(primitives
				(gr_poly
					(pts
						(arc
							(start -0.1778 -0.2794)
							(mid -0.249642 -0.249642)
							(end -0.2794 -0.1778)
						)
						(arc
							(start -0.2794 0.1778)
							(mid -0.249642 0.249642)
							(end -0.1778 0.2794)
						)
						(arc
							(start 0.1778 0.2794)
							(mid 0.249642 0.249642)
							(end 0.2794 0.1778)
						)
						(arc
							(start 0.2794 -0.1778)
							(mid 0.249642 -0.249642)
							(end 0.1778 -0.2794)
						)
					)
					(width 0)
					(fill yes)
				)
			)
		)
		(pad "2" smd custom
			(at 0 0.4445 90)
			(size 0.1397 0.1397)
			(layers "F.Cu" "F.Mask" "F.Paste")
			(net "I2C_DPB_A_SCL_BUF")
			(options
				(clearance outline)
				(anchor circle)
			)
			(primitives
				(gr_poly
					(pts
						(arc
							(start -0.1778 -0.2794)
							(mid -0.249642 -0.249642)
							(end -0.2794 -0.1778)
						)
						(arc
							(start -0.2794 0.1778)
							(mid -0.249642 0.249642)
							(end -0.1778 0.2794)
						)
						(arc
							(start 0.1778 0.2794)
							(mid 0.249642 0.249642)
							(end 0.2794 0.1778)
						)
						(arc
							(start 0.2794 -0.1778)
							(mid 0.249642 -0.249642)
							(end 0.1778 -0.2794)
						)
					)
					(width 0)
					(fill yes)
				)
			)
		)
	)
	(footprint ""
		(layer "F.Cu")
		(at 159.324802 -178.799998)
		(property "Reference" ""
			(at 0 0 0)
			(layer "F.SilkS")
			(hide yes)
			(effects
				(font
					(size 1.27 1.27)
				)
			)
		)
		(property "Value" "*"
			(at -8.398764 -8.057642 0)
			(unlocked yes)
			(layer "F.Fab")
			(hide yes)
			(effects
				(font
					(size 1.016 1.016)
					(thickness 0.1524)
				)
			)
		)
		(duplicate_pad_numbers_are_jumpers no)
		(fp_poly
			(pts
				(arc
					(start 7.3152 0)
					(mid 0 7.3152)
					(end -7.3152 0)
				)
				(arc
					(start -7.3152 -5.9944)
					(mid 0 -13.3096)
					(end 7.3152 -5.9944)
				)
			)
			(stroke
				(width 0)
				(type default)
			)
			(fill no)
			(layer "B.CrtYd")
		)
		(fp_poly
			(pts
				(arc
					(start 7.3152 0)
					(mid 0 7.3152)
					(end -7.3152 0)
				)
				(arc
					(start -7.3152 -5.9944)
					(mid 0 -13.3096)
					(end 7.3152 -5.9944)
				)
			)
			(stroke
				(width 0)
				(type default)
			)
			(fill no)
			(layer "F.CrtYd")
		)
		(fp_poly
			(pts
				(arc
					(start 7.3152 0)
					(mid 0 7.3152)
					(end -7.3152 0)
				)
				(arc
					(start -7.3152 -5.9944)
					(mid 0 -13.3096)
					(end 7.3152 -5.9944)
				)
			)
			(stroke
				(width 0)
				(type default)
			)
			(fill no)
			(layer "B.Fab")
		)
		(fp_poly
			(pts
				(arc
					(start 7.3152 0)
					(mid 0 7.3152)
					(end -7.3152 0)
				)
				(arc
					(start -7.3152 -5.9944)
					(mid 0 -13.3096)
					(end 7.3152 -5.9944)
				)
			)
			(stroke
				(width 0)
				(type default)
			)
			(fill no)
			(layer "F.Fab")
		)
		(pad "1" thru_hole oval
			(at 0 0)
			(size 14.0208 20.0152)
			(drill 0.0254
				(offset 0 -2.9972)
			)
			(layers "*.Cu" "*.Mask")
			(remove_unused_layers no)
			(net "Net_45")
			(clearance -1.002284)
			(thermal_gap 0.1524)
			(padstack
				(mode front_inner_back)
				(layer "Inner"
					(shape custom)
					(size 2.928012 2.928012)
					(options
						(anchor circle)
					)
					(primitives
						(gr_poly
							(pts
								(arc
									(start 4.571746 -2.084324)
									(mid 0.000333 7.430372)
									(end -4.571492 -2.084324)
								)
								(arc
									(start -4.571492 -2.084324)
									(mid -3.570296 -3.611977)
									(end -2.875026 -5.30098)
								)
								(arc
									(start -2.875026 -5.30098)
									(mid 0.000217 -7.43089)
									(end 2.87528 -5.30098)
								)
								(arc
									(start 2.87528 -5.30098)
									(mid 3.570511 -3.611956)
									(end 4.571746 -2.084324)
								)
							)
							(width 0)
							(fill yes)
						)
					)
					(clearance 0.1524)
				)
				(layer "B.Cu"
					(shape oval)
					(size 14.0208 20.0152)
					(offset 0 -2.9972)
					(clearance -1.002284)
				)
			)
		)
		(zone
			(layers "F.Cu" "B.Cu" "In1.Cu" "In2.Cu" "In3.Cu" "In4.Cu" "In5.Cu" "In6.Cu")
			(hatch none 0.5)
			(connect_pads
				(clearance 0)
			)
			(min_thickness 0.25)
			(keepout
				(tracks not_allowed)
				(vias allowed)
				(pads allowed)
				(copperpour not_allowed)
				(footprints allowed)
			)
			(placement
				(enabled no)
				(sheetname "")
			)
			(fill
				(thermal_gap 0.5)
				(thermal_bridge_width 0.5)
				(island_removal_mode 0)
			)
			(polygon
				(pts
					(arc
						(start 152.314402 -184.794398)
						(mid 159.324802 -191.804798)
						(end 166.335202 -184.794398)
					)
					(arc
						(start 166.335202 -178.799998)
						(mid 159.324802 -171.789598)
						(end 152.314402 -178.799998)
					)
				)
			)
		)
	)
)
